(kicad_pcb
	(version 20260206)
	(generator "pcbnew")
	(generator_version "10.0")
	(general
		(thickness 1.6)
		(legacy_teardrops no)
	)
	(paper "A4")
	(title_block
		(title "timecard-production-celestica-r4006 — R4006-B0001-02_R01.brd")
		(comment 1 "Time Appliance Project (Time Card) / footprints 1034-1038 of 1113")
	)
	(layers
		(0 "F.Cu" signal "TOP")
		(4 "In1.Cu" signal "L02_GND1")
		(6 "In2.Cu" signal "L03_SIG1")
		(8 "In3.Cu" signal "L04_GND2")
		(10 "In4.Cu" signal "L05_VCC1")
		(12 "In5.Cu" signal "L06_VCC2")
		(14 "In6.Cu" signal "L07_GND3")
		(16 "In7.Cu" signal "L08_SIG2")
		(18 "In8.Cu" signal "L09_GND4")
		(2 "B.Cu" signal "BOTTOM")
		(9 "F.Adhes" user "F.Adhesive")
		(11 "B.Adhes" user "B.Adhesive")
		(13 "F.Paste" user "Package Geometry/Pastemask Top")
		(15 "B.Paste" user "Package Geometry/Pastemask Bottom")
		(5 "F.SilkS" user "Ref Des/Silkscreen Top")
		(7 "B.SilkS" user "Ref Des/Silkscreen Bottom")
		(1 "F.Mask" user "Board Geometry/Soldermask Top")
		(3 "B.Mask" user "Board Geometry/Soldermask Bottom")
		(17 "Dwgs.User" user "User.Drawings")
		(19 "Cmts.User" user "User.Comments")
		(21 "Eco1.User" user "User.Eco1")
		(23 "Eco2.User" user "User.Eco2")
		(25 "Edge.Cuts" user "Board Geometry/Outline")
		(27 "Margin" user)
		(31 "F.CrtYd" user "Package Geometry/Place Bound Top")
		(29 "B.CrtYd" user "Package Geometry/Place Bound Bottom")
		(35 "F.Fab" user "Ref Des/Assembly Top")
		(33 "B.Fab" user "Ref Des/Assembly Bottom")
	)
	(footprint ""
		(layer "B.Cu")
		(at 36.9824 -99.0854 180)
		(property "Reference" "R142"
			(at 4.4196 -0.62357 0)
			(unlocked yes)
			(layer "B.SilkS")
			(effects
				(font
					(size 0.7874 0.5842)
					(thickness 0.1524)
				)
				(justify mirror)
			)
		)
		(property "Value" "VAL*"
			(at -0.02032 2.13233 180)
			(unlocked yes)
			(layer "B.Fab")
			(hide yes)
			(effects
				(font
					(size 0.7874 0.5842)
					(thickness 0.1524)
				)
				(justify mirror)
			)
		)
		(property "Device Type" "RESISTOR-G155-11000-01,100OHM,A"
			(at -0.008382 1.210564 180)
			(unlocked yes)
			(layer "B.Fab")
			(hide yes)
			(effects
				(font
					(size 0.7874 0.5842)
					(thickness 0.1524)
				)
				(justify mirror)
			)
		)
		(property "User Part Number" "PARTNUM*"
			(at -0.02032 4.024884 180)
			(unlocked yes)
			(layer "Cmts.User")
			(hide yes)
			(effects
				(font
					(size 0.7874 0.5842)
					(thickness 0.1524)
				)
				(justify mirror)
			)
		)
		(property "Tolerance" "TOL*"
			(at -0.044704 3.05435 180)
			(unlocked yes)
			(layer "Cmts.User")
			(hide yes)
			(effects
				(font
					(size 0.7874 0.5842)
					(thickness 0.1524)
				)
				(justify mirror)
			)
		)
		(duplicate_pad_numbers_are_jumpers no)
		(fp_line
			(start 1.143 0.5588)
			(end -1.143 0.5588)
			(stroke
				(width 0.1)
				(type default)
			)
			(layer "B.SilkS")
		)
		(fp_line
			(start 1.143 -0.5588)
			(end 1.143 0.5588)
			(stroke
				(width 0.1)
				(type default)
			)
			(layer "B.SilkS")
		)
		(fp_line
			(start -1.143 0.5588)
			(end -1.143 -0.5588)
			(stroke
				(width 0.1)
				(type default)
			)
			(layer "B.SilkS")
		)
		(fp_line
			(start -1.143 -0.5588)
			(end 1.143 -0.5588)
			(stroke
				(width 0.1)
				(type default)
			)
			(layer "B.SilkS")
		)
		(fp_rect
			(start -1.143 0.5588)
			(end 1.143 -0.5588)
			(stroke
				(width 0)
				(type default)
			)
			(fill no)
			(layer "B.CrtYd")
		)
		(fp_line
			(start 0.508 0.3048)
			(end -0.508 0.3048)
			(stroke
				(width 0.1)
				(type default)
			)
			(layer "B.Fab")
		)
		(fp_line
			(start 0.508 -0.3048)
			(end 0.508 0.3048)
			(stroke
				(width 0.1)
				(type default)
			)
			(layer "B.Fab")
		)
		(fp_line
			(start -0.508 0.3048)
			(end -0.508 -0.3048)
			(stroke
				(width 0.1)
				(type default)
			)
			(layer "B.Fab")
		)
		(fp_line
			(start -0.508 -0.3048)
			(end 0.508 -0.3048)
			(stroke
				(width 0.1)
				(type default)
			)
			(layer "B.Fab")
		)
		(pad "1" smd rect
			(at 0.5334 0)
			(size 0.7112 0.6096)
			(layers "B.Cu" "B.Mask" "B.Paste")
			(net "XP1R8V_FPGA_PG")
		)
		(pad "2" smd rect
			(at -0.5334 0)
			(size 0.7112 0.6096)
			(layers "B.Cu" "B.Mask" "B.Paste")
			(net "R_XP5R0V_EN")
		)
		(zone
			(layer "B.Cu")
			(hatch none 0.5)
			(connect_pads
				(clearance 0)
			)
			(min_thickness 0.25)
			(keepout
				(tracks allowed)
				(vias not_allowed)
				(pads allowed)
				(copperpour not_allowed)
				(footprints allowed)
			)
			(placement
				(enabled no)
				(sheetname "")
			)
			(fill
				(thermal_gap 0.5)
				(thermal_bridge_width 0.5)
				(island_removal_mode 0)
			)
			(polygon
				(pts
					(xy 37.0586 -99.3902) (xy 36.9062 -99.3902) (xy 36.9062 -98.7806) (xy 37.0586 -98.7806)
				)
			)
		)
	)
	(footprint ""
		(layer "B.Cu")
		(at 117.729 -100.076)
		(property "Reference" "C273"
			(at -1.397 -1.48463 0)
			(unlocked yes)
			(layer "B.SilkS")
			(effects
				(font
					(size 0.7874 0.5842)
					(thickness 0.1524)
				)
				(justify mirror)
			)
		)
		(property "Value" "VAL*"
			(at -0.0762 2.067306 0)
			(unlocked yes)
			(layer "B.Fab")
			(hide yes)
			(effects
				(font
					(size 0.7874 0.5842)
					(thickness 0.1524)
				)
				(justify mirror)
			)
		)
		(property "Tolerance" "TOL*"
			(at -0.0762 3.032506 0)
			(unlocked yes)
			(layer "Cmts.User")
			(hide yes)
			(effects
				(font
					(size 0.7874 0.5842)
					(thickness 0.1524)
				)
				(justify mirror)
			)
		)
		(property "User Part Number" "PARTNUM*"
			(at -0.1016 4.023106 0)
			(unlocked yes)
			(layer "Cmts.User")
			(hide yes)
			(effects
				(font
					(size 0.7874 0.5842)
					(thickness 0.1524)
				)
				(justify mirror)
			)
		)
		(property "Device Type" "CAPACITOR-G105-0B104-CK,0.1UF,A"
			(at -0.0508 1.127506 0)
			(unlocked yes)
			(layer "B.Fab")
			(hide yes)
			(effects
				(font
					(size 0.7874 0.5842)
					(thickness 0.1524)
				)
				(justify mirror)
			)
		)
		(duplicate_pad_numbers_are_jumpers no)
		(fp_line
			(start -1.143 -0.5588)
			(end 1.143 -0.5588)
			(stroke
				(width 0.1)
				(type default)
			)
			(layer "B.SilkS")
		)
		(fp_line
			(start -1.143 0.5588)
			(end -1.143 -0.5588)
			(stroke
				(width 0.1)
				(type default)
			)
			(layer "B.SilkS")
		)
		(fp_line
			(start 1.143 -0.5588)
			(end 1.143 0.5588)
			(stroke
				(width 0.1)
				(type default)
			)
			(layer "B.SilkS")
		)
		(fp_line
			(start 1.143 0.5588)
			(end -1.143 0.5588)
			(stroke
				(width 0.1)
				(type default)
			)
			(layer "B.SilkS")
		)
		(fp_rect
			(start -1.143 -0.5588)
			(end 1.143 0.5588)
			(stroke
				(width 0)
				(type default)
			)
			(fill no)
			(layer "B.CrtYd")
		)
		(fp_line
			(start -0.508 -0.3048)
			(end 0.508 -0.3048)
			(stroke
				(width 0.1)
				(type default)
			)
			(layer "B.Fab")
		)
		(fp_line
			(start -0.508 0.3048)
			(end -0.508 -0.3048)
			(stroke
				(width 0.1)
				(type default)
			)
			(layer "B.Fab")
		)
		(fp_line
			(start 0.508 -0.3048)
			(end 0.508 0.3048)
			(stroke
				(width 0.1)
				(type default)
			)
			(layer "B.Fab")
		)
		(fp_line
			(start 0.508 0.3048)
			(end -0.508 0.3048)
			(stroke
				(width 0.1)
				(type default)
			)
			(layer "B.Fab")
		)
		(pad "1" smd rect
			(at 0.5334 0 180)
			(size 0.7112 0.6096)
			(layers "B.Cu" "B.Mask" "B.Paste")
			(net "XP3R3V_GPS")
		)
		(pad "2" smd rect
			(at -0.5334 0 180)
			(size 0.7112 0.6096)
			(layers "B.Cu" "B.Mask" "B.Paste")
			(net "SG")
		)
		(zone
			(layer "B.Cu")
			(hatch none 0.5)
			(connect_pads
				(clearance 0)
			)
			(min_thickness 0.25)
			(keepout
				(tracks allowed)
				(vias not_allowed)
				(pads allowed)
				(copperpour not_allowed)
				(footprints allowed)
			)
			(placement
				(enabled no)
				(sheetname "")
			)
			(fill
				(thermal_gap 0.5)
				(thermal_bridge_width 0.5)
				(island_removal_mode 0)
			)
			(polygon
				(pts
					(xy 117.6528 -100.3808) (xy 117.6528 -99.7712) (xy 117.8052 -99.7712) (xy 117.8052 -100.3808)
				)
			)
		)
	)
	(footprint ""
		(layer "B.Cu")
		(at 21.0566 -41.6306)
		(property "Reference" "R147"
			(at -0.3556 4.83997 0)
			(unlocked yes)
			(layer "B.SilkS")
			(effects
				(font
					(size 0.7874 0.5842)
					(thickness 0.1524)
				)
				(justify mirror)
			)
		)
		(property "Value" "VAL*"
			(at -0.02032 2.13233 0)
			(unlocked yes)
			(layer "B.Fab")
			(hide yes)
			(effects
				(font
					(size 0.7874 0.5842)
					(thickness 0.1524)
				)
				(justify mirror)
			)
		)
		(property "Device Type" "RESISTOR-G155-11002-01,10KOHM,A"
			(at -0.008382 1.210564 0)
			(unlocked yes)
			(layer "B.Fab")
			(hide yes)
			(effects
				(font
					(size 0.7874 0.5842)
					(thickness 0.1524)
				)
				(justify mirror)
			)
		)
		(property "User Part Number" "PARTNUM*"
			(at -0.02032 4.024884 0)
			(unlocked yes)
			(layer "Cmts.User")
			(hide yes)
			(effects
				(font
					(size 0.7874 0.5842)
					(thickness 0.1524)
				)
				(justify mirror)
			)
		)
		(property "Tolerance" "TOL*"
			(at -0.044704 3.05435 0)
			(unlocked yes)
			(layer "Cmts.User")
			(hide yes)
			(effects
				(font
					(size 0.7874 0.5842)
					(thickness 0.1524)
				)
				(justify mirror)
			)
		)
		(duplicate_pad_numbers_are_jumpers no)
		(fp_line
			(start -1.143 -0.5588)
			(end 1.143 -0.5588)
			(stroke
				(width 0.1)
				(type default)
			)
			(layer "B.SilkS")
		)
		(fp_line
			(start -1.143 0.5588)
			(end -1.143 -0.5588)
			(stroke
				(width 0.1)
				(type default)
			)
			(layer "B.SilkS")
		)
		(fp_line
			(start 1.143 -0.5588)
			(end 1.143 0.5588)
			(stroke
				(width 0.1)
				(type default)
			)
			(layer "B.SilkS")
		)
		(fp_line
			(start 1.143 0.5588)
			(end -1.143 0.5588)
			(stroke
				(width 0.1)
				(type default)
			)
			(layer "B.SilkS")
		)
		(fp_rect
			(start 1.143 0.5588)
			(end -1.143 -0.5588)
			(stroke
				(width 0)
				(type default)
			)
			(fill no)
			(layer "B.CrtYd")
		)
		(fp_line
			(start -0.508 -0.3048)
			(end 0.508 -0.3048)
			(stroke
				(width 0.1)
				(type default)
			)
			(layer "B.Fab")
		)
		(fp_line
			(start -0.508 0.3048)
			(end -0.508 -0.3048)
			(stroke
				(width 0.1)
				(type default)
			)
			(layer "B.Fab")
		)
		(fp_line
			(start 0.508 -0.3048)
			(end 0.508 0.3048)
			(stroke
				(width 0.1)
				(type default)
			)
			(layer "B.Fab")
		)
		(fp_line
			(start 0.508 0.3048)
			(end -0.508 0.3048)
			(stroke
				(width 0.1)
				(type default)
			)
			(layer "B.Fab")
		)
		(pad "1" smd rect
			(at 0.5334 0 180)
			(size 0.7112 0.6096)
			(layers "B.Cu" "B.Mask" "B.Paste")
			(net "XP3R3V_FPGA")
		)
		(pad "2" smd rect
			(at -0.5334 0 180)
			(size 0.7112 0.6096)
			(layers "B.Cu" "B.Mask" "B.Paste")
			(net "R_PCA9546_I2C_SDA")
		)
		(zone
			(layer "B.Cu")
			(hatch none 0.5)
			(connect_pads
				(clearance 0)
			)
			(min_thickness 0.25)
			(keepout
				(tracks allowed)
				(vias not_allowed)
				(pads allowed)
				(copperpour not_allowed)
				(footprints allowed)
			)
			(placement
				(enabled no)
				(sheetname "")
			)
			(fill
				(thermal_gap 0.5)
				(thermal_bridge_width 0.5)
				(island_removal_mode 0)
			)
			(polygon
				(pts
					(xy 21.1328 -41.3258) (xy 21.1328 -41.9354) (xy 20.9804 -41.9354) (xy 20.9804 -41.3258)
				)
			)
		)
	)
	(footprint ""
		(layer "B.Cu")
		(at 96.139 -33.909 90)
		(property "Reference" "C125"
			(at -2.19837 -0.889 0)
			(unlocked yes)
			(layer "B.SilkS")
			(effects
				(font
					(size 0.7874 0.5842)
					(thickness 0.1524)
				)
				(justify mirror)
			)
		)
		(property "Value" "VAL*"
			(at -0.0762 3.134106 90)
			(unlocked yes)
			(layer "B.Fab")
			(hide yes)
			(effects
				(font
					(size 0.7874 0.5842)
					(thickness 0.1524)
				)
				(justify mirror)
			)
		)
		(property "Tolerance" "TOL*"
			(at -0.0762 4.048506 90)
			(unlocked yes)
			(layer "Cmts.User")
			(hide yes)
			(effects
				(font
					(size 0.7874 0.5842)
					(thickness 0.1524)
				)
				(justify mirror)
			)
		)
		(property "User Part Number" "PARTNUM*"
			(at -0.1016 5.013706 90)
			(unlocked yes)
			(layer "Cmts.User")
			(hide yes)
			(effects
				(font
					(size 0.7874 0.5842)
					(thickness 0.1524)
				)
				(justify mirror)
			)
		)
		(property "Device Type" "CAPACITOR-G107-0F476-AM,47UF,2A"
			(at -0.0508 2.194306 90)
			(unlocked yes)
			(layer "B.Fab")
			(hide yes)
			(effects
				(font
					(size 0.7874 0.5842)
					(thickness 0.1524)
				)
				(justify mirror)
			)
		)
		(duplicate_pad_numbers_are_jumpers no)
		(fp_line
			(start 1.5748 -0.9398)
			(end 1.5748 0.9398)
			(stroke
				(width 0.1)
				(type default)
			)
			(layer "B.SilkS")
		)
		(fp_line
			(start -1.5748 -0.9398)
			(end 1.5748 -0.9398)
			(stroke
				(width 0.1)
				(type default)
			)
			(layer "B.SilkS")
		)
		(fp_line
			(start 1.5748 0.9398)
			(end -1.5748 0.9398)
			(stroke
				(width 0.1)
				(type default)
			)
			(layer "B.SilkS")
		)
		(fp_line
			(start -1.5748 0.9398)
			(end -1.5748 -0.9398)
			(stroke
				(width 0.1)
				(type default)
			)
			(layer "B.SilkS")
		)
		(fp_rect
			(start -1.5748 -0.9398)
			(end 1.5748 0.9398)
			(stroke
				(width 0)
				(type default)
			)
			(fill no)
			(layer "B.CrtYd")
		)
		(fp_line
			(start 1.016 -0.635)
			(end 1.016 0.635)
			(stroke
				(width 0.1)
				(type default)
			)
			(layer "B.Fab")
		)
		(fp_line
			(start -1.016 -0.635)
			(end 1.016 -0.635)
			(stroke
				(width 0.1)
				(type default)
			)
			(layer "B.Fab")
		)
		(fp_line
			(start 1.016 0.635)
			(end -1.016 0.635)
			(stroke
				(width 0.1)
				(type default)
			)
			(layer "B.Fab")
		)
		(fp_line
			(start -1.016 0.635)
			(end -1.016 -0.635)
			(stroke
				(width 0.1)
				(type default)
			)
			(layer "B.Fab")
		)
		(pad "1" smd rect
			(at 0.8382 0 270)
			(size 0.9652 1.3716)
			(layers "B.Cu" "B.Mask" "B.Paste")
			(net "FPGA_MGTAVTT")
		)
		(pad "2" smd rect
			(at -0.8382 0 270)
			(size 0.9652 1.3716)
			(layers "B.Cu" "B.Mask" "B.Paste")
			(net "SG")
		)
		(zone
			(layer "B.Cu")
			(hatch none 0.5)
			(connect_pads
				(clearance 0)
			)
			(min_thickness 0.25)
			(keepout
				(tracks allowed)
				(vias not_allowed)
				(pads allowed)
				(copperpour not_allowed)
				(footprints allowed)
			)
			(placement
				(enabled no)
				(sheetname "")
			)
			(fill
				(thermal_gap 0.5)
				(thermal_bridge_width 0.5)
				(island_removal_mode 0)
			)
			(polygon
				(pts
					(xy 95.504 -33.6804) (xy 96.774 -33.6804) (xy 96.774 -34.1376) (xy 95.504 -34.1376)
				)
			)
		)
	)
	(footprint ""
		(layer "B.Cu")
		(at 41.402 -89.535 90)
		(property "Reference" "C88"
			(at -2.413 -0.03937 270)
			(unlocked yes)
			(layer "B.SilkS")
			(effects
				(font
					(size 0.7874 0.5842)
					(thickness 0.1524)
				)
				(justify mirror)
			)
		)
		(property "Value" "VAL*"
			(at -0.0762 2.067306 90)
			(unlocked yes)
			(layer "B.Fab")
			(hide yes)
			(effects
				(font
					(size 0.7874 0.5842)
					(thickness 0.1524)
				)
				(justify mirror)
			)
		)
		(property "Device Type" "CAPACITOR-G105-0B104-EK,0.1UF,A"
			(at -0.0508 1.127506 90)
			(unlocked yes)
			(layer "B.Fab")
			(hide yes)
			(effects
				(font
					(size 0.7874 0.5842)
					(thickness 0.1524)
				)
				(justify mirror)
			)
		)
		(property "User Part Number" "PARTNUM*"
			(at -0.1016 4.023106 90)
			(unlocked yes)
			(layer "Cmts.User")
			(hide yes)
			(effects
				(font
					(size 0.7874 0.5842)
					(thickness 0.1524)
				)
				(justify mirror)
			)
		)
		(property "Tolerance" "TOL*"
			(at -0.0762 3.032506 90)
			(unlocked yes)
			(layer "Cmts.User")
			(hide yes)
			(effects
				(font
					(size 0.7874 0.5842)
					(thickness 0.1524)
				)
				(justify mirror)
			)
		)
		(duplicate_pad_numbers_are_jumpers no)
		(fp_line
			(start 1.143 -0.5588)
			(end 1.143 0.5588)
			(stroke
				(width 0.1)
				(type default)
			)
			(layer "B.SilkS")
		)
		(fp_line
			(start -1.143 -0.5588)
			(end 1.143 -0.5588)
			(stroke
				(width 0.1)
				(type default)
			)
			(layer "B.SilkS")
		)
		(fp_line
			(start 1.143 0.5588)
			(end -1.143 0.5588)
			(stroke
				(width 0.1)
				(type default)
			)
			(layer "B.SilkS")
		)
		(fp_line
			(start -1.143 0.5588)
			(end -1.143 -0.5588)
			(stroke
				(width 0.1)
				(type default)
			)
			(layer "B.SilkS")
		)
		(fp_rect
			(start 1.143 -0.5588)
			(end -1.143 0.5588)
			(stroke
				(width 0)
				(type default)
			)
			(fill no)
			(layer "B.CrtYd")
		)
		(fp_line
			(start 0.508 -0.3048)
			(end 0.508 0.3048)
			(stroke
				(width 0.1)
				(type default)
			)
			(layer "B.Fab")
		)
		(fp_line
			(start -0.508 -0.3048)
			(end 0.508 -0.3048)
			(stroke
				(width 0.1)
				(type default)
			)
			(layer "B.Fab")
		)
		(fp_line
			(start 0.508 0.3048)
			(end -0.508 0.3048)
			(stroke
				(width 0.1)
				(type default)
			)
			(layer "B.Fab")
		)
		(fp_line
			(start -0.508 0.3048)
			(end -0.508 -0.3048)
			(stroke
				(width 0.1)
				(type default)
			)
			(layer "B.Fab")
		)
		(pad "1" smd rect
			(at 0.5334 0 270)
			(size 0.7112 0.6096)
			(layers "B.Cu" "B.Mask" "B.Paste")
			(net "XP3R3V_FT4232")
		)
		(pad "2" smd rect
			(at -0.5334 0 270)
			(size 0.7112 0.6096)
			(layers "B.Cu" "B.Mask" "B.Paste")
			(net "SG")
		)
		(zone
			(layer "B.Cu")
			(hatch none 0.5)
			(connect_pads
				(clearance 0)
			)
			(min_thickness 0.25)
			(keepout
				(tracks allowed)
				(vias not_allowed)
				(pads allowed)
				(copperpour not_allowed)
				(footprints allowed)
			)
			(placement
				(enabled no)
				(sheetname "")
			)
			(fill
				(thermal_gap 0.5)
				(thermal_bridge_width 0.5)
				(island_removal_mode 0)
			)
			(polygon
				(pts
					(xy 41.0972 -89.6112) (xy 41.0972 -89.4588) (xy 41.7068 -89.4588) (xy 41.7068 -89.6112)
				)
			)
		)
	)
)
